# BASEBOARD_FAB2 (Tioga Pass) — schematic netlist excerpt (pin names and nets, part order shuffled) for the footprints in the layout excerpt that follows; sources: Cadence DE-HDL packaged netlist, KiCad conversion of Wiwynn_Tioga_Pass_MB.brd

RT39  1R3F-GP  1%  pkg RCL_GP  page 205 : \1\ = VR_PVSA_CPU0_PHASE_SW_RC ; \2\ = GND
C4A16  CAP  3300PF 50V 10% EMPTY  pkg 0402LF  page 234 : A = VR_PVPP_KLM_PHASE ; B = VR_PVPP_KLM_SNUB

U4G1  PCA9617  IC  pkg SSOP  page 99
  VCCA  = PVCCIO_CPU1
  SCLA  = SMB_DDR_GHJ_SCL_G
  SDAA  = SMB_DDR_GHJ_SDA_G
  EN  = TP_SMB_DDR_GHJ_EN
  SDAB  = SMB_DDR_GHJ_VPP_SDA_R
  SCLB  = SMB_DDR_GHJ_VPP_SCL_R
  VCCB  = PVPP_GHJ

(kicad_pcb
	(version 20260206)
	(generator "pcbnew")
	(generator_version "10.0")
	(general
		(thickness 1.6)
		(legacy_teardrops no)
	)
	(paper "A4")
	(title_block
		(title "Wiwynn_Tioga_Pass_MB.brd")
		(comment 1 "Tioga Pass / footprints 2109-2111 of 4770")
	)
	(layers
		(0 "F.Cu" signal "TOP")
		(4 "In1.Cu" signal "L2GND")
		(6 "In2.Cu" signal "L3")
		(8 "In3.Cu" signal "L4GND")
		(10 "In4.Cu" signal "L5")
		(12 "In5.Cu" signal "L6GND")
		(14 "In6.Cu" signal "L7VCC")
		(16 "In7.Cu" signal "L8VCC")
		(18 "In8.Cu" signal "L9GND")
		(20 "In9.Cu" signal "L10")
		(22 "In10.Cu" signal "L11GND")
		(24 "In11.Cu" signal "L12")
		(26 "In12.Cu" signal "L13GND")
		(2 "B.Cu" signal "BOTTOM")
		(9 "F.Adhes" user "F.Adhesive")
		(11 "B.Adhes" user "B.Adhesive")
		(13 "F.Paste" user "Package Geometry/Pastemask Top")
		(15 "B.Paste" user "Package Geometry/Pastemask Bottom")
		(5 "F.SilkS" user "Ref Des/Silkscreen Top")
		(7 "B.SilkS" user "Ref Des/Silkscreen Bottom")
		(1 "F.Mask" user "Board Geometry/Soldermask Top")
		(3 "B.Mask" user "Board Geometry/Soldermask Bottom")
		(17 "Dwgs.User" user "User.Drawings")
		(19 "Cmts.User" user "User.Comments")
		(21 "Eco1.User" user "User.Eco1")
		(23 "Eco2.User" user "User.Eco2")
		(25 "Edge.Cuts" user "Board Geometry/Outline")
		(27 "Margin" user)
		(31 "F.CrtYd" user "Package Geometry/Place Bound Top")
		(29 "B.CrtYd" user "Package Geometry/Place Bound Bottom")
		(35 "F.Fab" user "Ref Des/Assembly Top")
		(33 "B.Fab" user "Ref Des/Assembly Bottom")
	)
	(footprint ""
		(layer "F.Cu")
		(at 174.244 -141.1605 90)
		(property "Reference" "C4A16"
			(at 0 0 90)
			(layer "F.SilkS")
			(hide yes)
			(effects
				(font
					(size 1.27 1.27)
				)
			)
		)
		(property "Value" ""
			(at 0 0 90)
			(layer "F.Fab")
			(effects
				(font
					(size 1.27 1.27)
				)
			)
		)
		(duplicate_pad_numbers_are_jumpers no)
		(fp_poly
			(pts
				(xy 0.3048 -0.1016) (xy 0.3048 0.9906) (xy -0.3048 0.9906) (xy -0.3048 -0.1016)
			)
			(stroke
				(width 0)
				(type default)
			)
			(fill no)
			(layer "F.CrtYd")
		)
		(fp_line
			(start 0.3048 -0.1016)
			(end -0.3048 -0.1016)
			(stroke
				(width 0.1)
				(type default)
			)
			(layer "F.Fab")
		)
		(fp_line
			(start -0.3048 -0.1016)
			(end -0.3048 0.9906)
			(stroke
				(width 0.1)
				(type default)
			)
			(layer "F.Fab")
		)
		(fp_line
			(start 0.3048 0.9906)
			(end 0.3048 -0.1016)
			(stroke
				(width 0.1)
				(type default)
			)
			(layer "F.Fab")
		)
		(fp_line
			(start -0.3048 0.9906)
			(end 0.3048 0.9906)
			(stroke
				(width 0.1)
				(type default)
			)
			(layer "F.Fab")
		)
		(pad "1" smd rect
			(at 0 0 90)
			(size 0.508 0.508)
			(layers "F.Cu" "F.Mask" "F.Paste")
			(net "VR_PVPP_KLM_PHASE")
		)
		(pad "2" smd rect
			(at 0 0.889 90)
			(size 0.508 0.508)
			(layers "F.Cu" "F.Mask" "F.Paste")
			(net "VR_PVPP_KLM_SNUB")
		)
		(zone
			(layer "F.Cu")
			(hatch none 0.5)
			(connect_pads
				(clearance 0)
			)
			(min_thickness 0.25)
			(keepout
				(tracks allowed)
				(vias not_allowed)
				(pads allowed)
				(copperpour not_allowed)
				(footprints allowed)
			)
			(placement
				(enabled no)
				(sheetname "")
			)
			(fill
				(thermal_gap 0.5)
				(thermal_bridge_width 0.5)
				(island_removal_mode 0)
			)
			(polygon
				(pts
					(xy 174.498 -140.9065) (xy 174.498 -141.4145) (xy 174.879 -141.4145) (xy 174.879 -140.9065)
				)
			)
		)
		(zone
			(layer "F.Cu")
			(hatch none 0.5)
			(connect_pads
				(clearance 0)
			)
			(min_thickness 0.25)
			(keepout
				(tracks not_allowed)
				(vias allowed)
				(pads allowed)
				(copperpour not_allowed)
				(footprints allowed)
			)
			(placement
				(enabled no)
				(sheetname "")
			)
			(fill
				(thermal_gap 0.5)
				(thermal_bridge_width 0.5)
				(island_removal_mode 0)
			)
			(polygon
				(pts
					(xy 174.879 -140.9065) (xy 174.879 -141.4145) (xy 174.498 -141.4145) (xy 174.498 -140.9065)
				)
			)
		)
	)
	(footprint ""
		(layer "F.Cu")
		(at 200.604628 -93.577918 -90)
		(property "Reference" "RT39"
			(at 0 0 270)
			(layer "F.SilkS")
			(hide yes)
			(effects
				(font
					(size 1.27 1.27)
				)
			)
		)
		(property "Value" "*"
			(at -0.0254 -2.6289 270)
			(unlocked yes)
			(layer "F.Fab")
			(hide yes)
			(effects
				(font
					(size 1.27 1.016)
					(thickness 0.1524)
				)
			)
		)
		(property "Device Type" "1R3F-GP_RCL_GP-1R3F-GP,64.1R00A"
			(at -0.0254 -4.1529 270)
			(unlocked yes)
			(layer "F.Fab")
			(hide yes)
			(effects
				(font
					(size 1.27 1.016)
					(thickness 0.1524)
				)
			)
		)
		(duplicate_pad_numbers_are_jumpers no)
		(fp_line
			(start -0.4826 0)
			(end -0.2032 0)
			(stroke
				(width 0.2032)
				(type default)
			)
			(layer "F.SilkS")
		)
		(fp_line
			(start 0.2032 0)
			(end 0.4826 0)
			(stroke
				(width 0.2032)
				(type default)
			)
			(layer "F.SilkS")
		)
		(fp_rect
			(start -0.5842 1.3335)
			(end 0.5842 -1.3335)
			(stroke
				(width 0)
				(type default)
			)
			(fill no)
			(layer "F.CrtYd")
		)
		(fp_rect
			(start -0.5842 1.3335)
			(end 0.5842 -1.3335)
			(stroke
				(width 0)
				(type default)
			)
			(fill no)
			(layer "F.Fab")
		)
		(pad "1" smd custom
			(at 0 -0.762 270)
			(size 0.2159 0.2159)
			(layers "F.Cu" "F.Mask" "F.Paste")
			(net "VR_PVSA_CPU0_PHASE_SW_RC")
			(options
				(clearance outline)
				(anchor circle)
			)
			(primitives
				(gr_poly
					(pts
						(arc
							(start -0.3302 -0.4318)
							(mid -0.402042 -0.402042)
							(end -0.4318 -0.3302)
						)
						(arc
							(start -0.4318 0.3302)
							(mid -0.402042 0.402042)
							(end -0.3302 0.4318)
						)
						(arc
							(start 0.3302 0.4318)
							(mid 0.402042 0.402042)
							(end 0.4318 0.3302)
						)
						(arc
							(start 0.4318 -0.3302)
							(mid 0.402042 -0.402042)
							(end 0.3302 -0.4318)
						)
					)
					(width 0)
					(fill yes)
				)
			)
		)
		(pad "2" smd custom
			(at 0 0.762 270)
			(size 0.2159 0.2159)
			(layers "F.Cu" "F.Mask" "F.Paste")
			(net "GND")
			(options
				(clearance outline)
				(anchor circle)
			)
			(primitives
				(gr_poly
					(pts
						(arc
							(start -0.3302 -0.4318)
							(mid -0.402042 -0.402042)
							(end -0.4318 -0.3302)
						)
						(arc
							(start -0.4318 0.3302)
							(mid -0.402042 0.402042)
							(end -0.3302 0.4318)
						)
						(arc
							(start 0.3302 0.4318)
							(mid 0.402042 0.402042)
							(end 0.4318 0.3302)
						)
						(arc
							(start 0.4318 -0.3302)
							(mid 0.402042 -0.402042)
							(end 0.3302 -0.4318)
						)
					)
					(width 0)
					(fill yes)
				)
			)
		)
	)
	(footprint ""
		(layer "F.Cu")
		(at 166.9415 -0.77978 -90)
		(property "Reference" "U4G1"
			(at -3.00482 2.09423 90)
			(unlocked yes)
			(layer "F.SilkS")
			(effects
				(font
					(size 0.7874 0.5842)
					(thickness 0.1524)
				)
			)
		)
		(property "Value" ""
			(at 0 0 270)
			(layer "F.Fab")
			(effects
				(font
					(size 1.27 1.27)
				)
			)
		)
		(duplicate_pad_numbers_are_jumpers no)
		(fp_line
			(start 3.225038 2.52476)
			(end 1.348486 2.52476)
			(stroke
				(width 0.1524)
				(type default)
			)
			(layer "F.SilkS")
		)
		(fp_line
			(start 3.225292 -0.57404)
			(end 1.352804 -0.57404)
			(stroke
				(width 0.1524)
				(type default)
			)
			(layer "F.SilkS")
		)
		(fp_circle
			(center -1.454404 -0.556514)
			(end -1.454404 -0.683514)
			(stroke
				(width 0.254)
				(type default)
			)
			(fill no)
			(layer "F.SilkS")
		)
		(fp_poly
			(pts
				(xy 0.7366 -0.57404) (xy 3.8354 -0.57404) (xy 3.8354 2.52476) (xy 0.7366 2.52476)
			)
			(stroke
				(width 0)
				(type default)
			)
			(fill no)
			(layer "F.CrtYd")
		)
		(fp_line
			(start 0.7366 2.52476)
			(end 0.7366 -0.57404)
			(stroke
				(width 0.1)
				(type default)
			)
			(layer "F.Fab")
		)
		(fp_line
			(start 3.8354 2.52476)
			(end 0.7366 2.52476)
			(stroke
				(width 0.1)
				(type default)
			)
			(layer "F.Fab")
		)
		(fp_line
			(start 0.7366 -0.57404)
			(end 3.8354 -0.57404)
			(stroke
				(width 0.1)
				(type default)
			)
			(layer "F.Fab")
		)
		(fp_line
			(start 3.8354 -0.57404)
			(end 3.8354 2.52476)
			(stroke
				(width 0.1)
				(type default)
			)
			(layer "F.Fab")
		)
		(fp_circle
			(center -1.454404 -0.556514)
			(end -1.454404 -0.683514)
			(stroke
				(width 0.254)
				(type default)
			)
			(fill no)
			(layer "F.Fab")
		)
		(pad "1" smd rect
			(at 0 0 270)
			(size 1.778 0.4572)
			(layers "F.Cu" "F.Mask" "F.Paste")
			(net "PVCCIO_CPU1")
		)
		(pad "2" smd rect
			(at 0 0.65024 270)
			(size 1.778 0.4572)
			(layers "F.Cu" "F.Mask" "F.Paste")
			(net "SMB_DDR_GHJ_SCL_G")
		)
		(pad "3" smd rect
			(at 0 1.30048 270)
			(size 1.778 0.4572)
			(layers "F.Cu" "F.Mask" "F.Paste")
			(net "SMB_DDR_GHJ_SDA_G")
		)
		(pad "4" smd rect
			(at 0 1.95072 270)
			(size 1.778 0.4572)
			(layers "F.Cu" "F.Mask" "F.Paste")
			(net "GND")
		)
		(pad "5" smd rect
			(at 4.572 1.95072 270)
			(size 1.778 0.4572)
			(layers "F.Cu" "F.Mask" "F.Paste")
			(net "TP_SMB_DDR_GHJ_EN")
		)
		(pad "6" smd rect
			(at 4.572 1.30048 270)
			(size 1.778 0.4572)
			(layers "F.Cu" "F.Mask" "F.Paste")
			(net "SMB_DDR_GHJ_VPP_SDA_R")
		)
		(pad "7" smd rect
			(at 4.572 0.65024 270)
			(size 1.778 0.4572)
			(layers "F.Cu" "F.Mask" "F.Paste")
			(net "SMB_DDR_GHJ_VPP_SCL_R")
		)
		(pad "8" smd rect
			(at 4.572 0 270)
			(size 1.778 0.4572)
			(layers "F.Cu" "F.Mask" "F.Paste")
			(net "PVPP_GHJ")
		)
	)
)
